(kicad_pcb
	(version 20260206)
	(generator "pcbnew")
	(generator_version "10.0")
	(general
		(thickness 1.6)
		(legacy_teardrops no)
	)
	(paper "A4")
	(title_block
		(title "pdpb — Lightning_PDPB_BRD.brd")
		(comment 1 "Lightning (Wiwynn / Facebook NVMe JBOF) / footprints 974-980 of 1140")
	)
	(layers
		(0 "F.Cu" signal "TOP")
		(4 "In1.Cu" signal "L2GND")
		(6 "In2.Cu" signal "L3")
		(8 "In3.Cu" signal "L4VCC")
		(10 "In4.Cu" signal "L5VCC")
		(12 "In5.Cu" signal "L6")
		(14 "In6.Cu" signal "L7GND")
		(2 "B.Cu" signal "BOTTOM")
		(9 "F.Adhes" user "F.Adhesive")
		(11 "B.Adhes" user "B.Adhesive")
		(13 "F.Paste" user "Package Geometry/Pastemask Top")
		(15 "B.Paste" user "Package Geometry/Pastemask Bottom")
		(5 "F.SilkS" user "Ref Des/Silkscreen Top")
		(7 "B.SilkS" user "Ref Des/Silkscreen Bottom")
		(1 "F.Mask" user "Board Geometry/Soldermask Top")
		(3 "B.Mask" user "Board Geometry/Soldermask Bottom")
		(17 "Dwgs.User" user "User.Drawings")
		(19 "Cmts.User" user "User.Comments")
		(21 "Eco1.User" user "User.Eco1")
		(23 "Eco2.User" user "User.Eco2")
		(25 "Edge.Cuts" user "Board Geometry/Outline")
		(27 "Margin" user)
		(31 "F.CrtYd" user "Package Geometry/Place Bound Top")
		(29 "B.CrtYd" user "Package Geometry/Place Bound Bottom")
		(35 "F.Fab" user "Ref Des/Assembly Top")
		(33 "B.Fab" user "Ref Des/Assembly Bottom")
	)
	(footprint ""
		(layer "F.Cu")
		(at 206.883 -437.769 90)
		(property "Reference" "PR9087"
			(at 0 0 90)
			(layer "F.SilkS")
			(hide yes)
			(effects
				(font
					(size 1.27 1.27)
				)
			)
		)
		(property "Value" "0R6J-3-GP"
			(at -0.0508 -4.8514 90)
			(unlocked yes)
			(layer "F.Fab")
			(hide yes)
			(effects
				(font
					(size 1.016 1.016)
					(thickness 0.1524)
				)
			)
		)
		(property "Device Type" "R1206H28"
			(at 0 -6.3754 90)
			(unlocked yes)
			(layer "F.Fab")
			(hide yes)
			(effects
				(font
					(size 1.016 1.016)
					(thickness 0.1524)
				)
			)
		)
		(duplicate_pad_numbers_are_jumpers no)
		(fp_line
			(start 1.016 -2.2352)
			(end 1.016 2.2352)
			(stroke
				(width 0.1524)
				(type default)
			)
			(layer "F.SilkS")
		)
		(fp_line
			(start -1.016 -2.2352)
			(end 1.016 -2.2352)
			(stroke
				(width 0.1524)
				(type default)
			)
			(layer "F.SilkS")
		)
		(fp_line
			(start 1.016 2.2352)
			(end -1.016 2.2352)
			(stroke
				(width 0.1524)
				(type default)
			)
			(layer "F.SilkS")
		)
		(fp_line
			(start -1.016 2.2352)
			(end -1.016 -2.2352)
			(stroke
				(width 0.1524)
				(type default)
			)
			(layer "F.SilkS")
		)
		(fp_rect
			(start -1.0922 2.3114)
			(end 1.0922 -2.3114)
			(stroke
				(width 0)
				(type default)
			)
			(fill no)
			(layer "F.CrtYd")
		)
		(fp_poly
			(pts
				(xy -1.0922 -2.3114) (xy 1.0922 -2.3114) (xy 1.0922 2.3114) (xy -1.0922 2.3114)
			)
			(stroke
				(width 0)
				(type default)
			)
			(fill no)
			(layer "F.Fab")
		)
		(pad "1" smd rect
			(at 0 -1.397 90)
			(size 1.651 1.27)
			(layers "F.Cu" "F.Mask" "F.Paste")
			(net "P3V3")
		)
		(pad "2" smd rect
			(at 0 1.397 90)
			(size 1.651 1.27)
			(layers "F.Cu" "F.Mask" "F.Paste")
			(net "P3V3_OUT")
		)
	)
	(footprint ""
		(layer "F.Cu")
		(at 213.3981 -94.5261 180)
		(property "Reference" "R9806"
			(at 0 0 180)
			(layer "F.SilkS")
			(hide yes)
			(effects
				(font
					(size 1.27 1.27)
				)
			)
		)
		(property "Value" "47KR2J-2-GP"
			(at 0.064008 -3.993896 180)
			(unlocked yes)
			(layer "F.Fab")
			(hide yes)
			(effects
				(font
					(size 1.016 1.016)
					(thickness 0.1524)
				)
			)
		)
		(property "Device Type" "R402H16"
			(at 0.064008 -5.517896 180)
			(unlocked yes)
			(layer "F.Fab")
			(hide yes)
			(effects
				(font
					(size 1.016 1.016)
					(thickness 0.1524)
				)
			)
		)
		(duplicate_pad_numbers_are_jumpers no)
		(fp_line
			(start 0.508 -0.9398)
			(end -0.508 -0.9398)
			(stroke
				(width 0.1524)
				(type default)
			)
			(layer "F.SilkS")
		)
		(fp_line
			(start -0.508 -0.9398)
			(end -0.508 0.9398)
			(stroke
				(width 0.1524)
				(type default)
			)
			(layer "F.SilkS")
		)
		(fp_rect
			(start -0.508 0.9398)
			(end 0.508 -0.9398)
			(stroke
				(width 0)
				(type default)
			)
			(fill no)
			(layer "F.CrtYd")
		)
		(fp_rect
			(start -0.508 0.9398)
			(end 0.508 -0.9398)
			(stroke
				(width 0)
				(type default)
			)
			(fill no)
			(layer "F.Fab")
		)
		(pad "1" smd custom
			(at 0 -0.4445 180)
			(size 0.1397 0.1397)
			(layers "F.Cu" "F.Mask" "F.Paste")
			(net "P12V")
			(options
				(clearance outline)
				(anchor circle)
			)
			(primitives
				(gr_poly
					(pts
						(arc
							(start -0.1778 -0.2794)
							(mid -0.249642 -0.249642)
							(end -0.2794 -0.1778)
						)
						(arc
							(start -0.2794 0.1778)
							(mid -0.249642 0.249642)
							(end -0.1778 0.2794)
						)
						(arc
							(start 0.1778 0.2794)
							(mid 0.249642 0.249642)
							(end 0.2794 0.1778)
						)
						(arc
							(start 0.2794 -0.1778)
							(mid 0.249642 -0.249642)
							(end 0.1778 -0.2794)
						)
					)
					(width 0)
					(fill yes)
				)
			)
		)
		(pad "2" smd custom
			(at 0 0.4445 180)
			(size 0.1397 0.1397)
			(layers "F.Cu" "F.Mask" "F.Paste")
			(net "P12V_MOST4_GATE")
			(options
				(clearance outline)
				(anchor circle)
			)
			(primitives
				(gr_poly
					(pts
						(arc
							(start -0.1778 -0.2794)
							(mid -0.249642 -0.249642)
							(end -0.2794 -0.1778)
						)
						(arc
							(start -0.2794 0.1778)
							(mid -0.249642 0.249642)
							(end -0.1778 0.2794)
						)
						(arc
							(start 0.1778 0.2794)
							(mid 0.249642 0.249642)
							(end 0.2794 0.1778)
						)
						(arc
							(start 0.2794 -0.1778)
							(mid 0.249642 -0.249642)
							(end 0.1778 -0.2794)
						)
					)
					(width 0)
					(fill yes)
				)
			)
		)
	)
	(footprint ""
		(layer "F.Cu")
		(at 83.185 -150.622 -90)
		(property "Reference" "SR1049"
			(at 0 0 270)
			(layer "F.SilkS")
			(hide yes)
			(effects
				(font
					(size 1.27 1.27)
				)
			)
		)
		(property "Value" "4K7R2F-GP"
			(at 0.064008 -3.993896 270)
			(unlocked yes)
			(layer "F.Fab")
			(hide yes)
			(effects
				(font
					(size 1.016 1.016)
					(thickness 0.1524)
				)
			)
		)
		(property "Device Type" "R402H16"
			(at 0.064008 -5.517896 270)
			(unlocked yes)
			(layer "F.Fab")
			(hide yes)
			(effects
				(font
					(size 1.016 1.016)
					(thickness 0.1524)
				)
			)
		)
		(duplicate_pad_numbers_are_jumpers no)
		(fp_line
			(start -0.508 -0.9398)
			(end -0.508 0.9398)
			(stroke
				(width 0.1524)
				(type default)
			)
			(layer "F.SilkS")
		)
		(fp_line
			(start 0.508 -0.9398)
			(end -0.508 -0.9398)
			(stroke
				(width 0.1524)
				(type default)
			)
			(layer "F.SilkS")
		)
		(fp_rect
			(start -0.508 0.9398)
			(end 0.508 -0.9398)
			(stroke
				(width 0)
				(type default)
			)
			(fill no)
			(layer "F.CrtYd")
		)
		(fp_rect
			(start -0.508 0.9398)
			(end 0.508 -0.9398)
			(stroke
				(width 0)
				(type default)
			)
			(fill no)
			(layer "F.Fab")
		)
		(pad "1" smd custom
			(at 0 -0.4445 270)
			(size 0.1397 0.1397)
			(layers "F.Cu" "F.Mask" "F.Paste")
			(net "P3V3")
			(options
				(clearance outline)
				(anchor circle)
			)
			(primitives
				(gr_poly
					(pts
						(arc
							(start -0.1778 -0.2794)
							(mid -0.249642 -0.249642)
							(end -0.2794 -0.1778)
						)
						(arc
							(start -0.2794 0.1778)
							(mid -0.249642 0.249642)
							(end -0.1778 0.2794)
						)
						(arc
							(start 0.1778 0.2794)
							(mid 0.249642 0.249642)
							(end 0.2794 0.1778)
						)
						(arc
							(start 0.2794 -0.1778)
							(mid 0.249642 -0.249642)
							(end 0.1778 -0.2794)
						)
					)
					(width 0)
					(fill yes)
				)
			)
		)
		(pad "2" smd custom
			(at 0 0.4445 270)
			(size 0.1397 0.1397)
			(layers "F.Cu" "F.Mask" "F.Paste")
			(net "I2C_SW_EU16_ADDRESS_A0")
			(options
				(clearance outline)
				(anchor circle)
			)
			(primitives
				(gr_poly
					(pts
						(arc
							(start -0.1778 -0.2794)
							(mid -0.249642 -0.249642)
							(end -0.2794 -0.1778)
						)
						(arc
							(start -0.2794 0.1778)
							(mid -0.249642 0.249642)
							(end -0.1778 0.2794)
						)
						(arc
							(start 0.1778 0.2794)
							(mid 0.249642 0.249642)
							(end 0.2794 0.1778)
						)
						(arc
							(start 0.2794 -0.1778)
							(mid 0.249642 -0.249642)
							(end 0.1778 -0.2794)
						)
					)
					(width 0)
					(fill yes)
				)
			)
		)
	)
	(footprint ""
		(layer "F.Cu")
		(at 230.632 -243.199158 -90)
		(property "Reference" "R9797"
			(at 0 0 270)
			(layer "F.SilkS")
			(hide yes)
			(effects
				(font
					(size 1.27 1.27)
				)
			)
		)
		(property "Value" "0R2J-2-GP"
			(at 0.064008 -3.993896 270)
			(unlocked yes)
			(layer "F.Fab")
			(hide yes)
			(effects
				(font
					(size 1.016 1.016)
					(thickness 0.1524)
				)
			)
		)
		(property "Device Type" "R402H16"
			(at 0.064008 -5.517896 270)
			(unlocked yes)
			(layer "F.Fab")
			(hide yes)
			(effects
				(font
					(size 1.016 1.016)
					(thickness 0.1524)
				)
			)
		)
		(duplicate_pad_numbers_are_jumpers no)
		(fp_line
			(start -0.508 -0.9398)
			(end -0.508 0.9398)
			(stroke
				(width 0.1524)
				(type default)
			)
			(layer "F.SilkS")
		)
		(fp_line
			(start 0.508 -0.9398)
			(end -0.508 -0.9398)
			(stroke
				(width 0.1524)
				(type default)
			)
			(layer "F.SilkS")
		)
		(fp_rect
			(start -0.508 0.9398)
			(end 0.508 -0.9398)
			(stroke
				(width 0)
				(type default)
			)
			(fill no)
			(layer "F.CrtYd")
		)
		(fp_rect
			(start -0.508 0.9398)
			(end 0.508 -0.9398)
			(stroke
				(width 0)
				(type default)
			)
			(fill no)
			(layer "F.Fab")
		)
		(pad "1" smd custom
			(at 0 -0.4445 270)
			(size 0.1397 0.1397)
			(layers "F.Cu" "F.Mask" "F.Paste")
			(net "SSD_ACT_DR2_R")
			(options
				(clearance outline)
				(anchor circle)
			)
			(primitives
				(gr_poly
					(pts
						(arc
							(start -0.1778 -0.2794)
							(mid -0.249642 -0.249642)
							(end -0.2794 -0.1778)
						)
						(arc
							(start -0.2794 0.1778)
							(mid -0.249642 0.249642)
							(end -0.1778 0.2794)
						)
						(arc
							(start 0.1778 0.2794)
							(mid 0.249642 0.249642)
							(end 0.2794 0.1778)
						)
						(arc
							(start 0.2794 -0.1778)
							(mid 0.249642 -0.249642)
							(end 0.1778 -0.2794)
						)
					)
					(width 0)
					(fill yes)
				)
			)
		)
		(pad "2" smd custom
			(at 0 0.4445 270)
			(size 0.1397 0.1397)
			(layers "F.Cu" "F.Mask" "F.Paste")
			(net "SSD_ACT_DR2")
			(options
				(clearance outline)
				(anchor circle)
			)
			(primitives
				(gr_poly
					(pts
						(arc
							(start -0.1778 -0.2794)
							(mid -0.249642 -0.249642)
							(end -0.2794 -0.1778)
						)
						(arc
							(start -0.2794 0.1778)
							(mid -0.249642 0.249642)
							(end -0.1778 0.2794)
						)
						(arc
							(start 0.1778 0.2794)
							(mid 0.249642 0.249642)
							(end 0.2794 0.1778)
						)
						(arc
							(start 0.2794 -0.1778)
							(mid 0.249642 -0.249642)
							(end 0.1778 -0.2794)
						)
					)
					(width 0)
					(fill yes)
				)
			)
		)
	)
	(footprint ""
		(layer "F.Cu")
		(at 24.892 -262.886952 90)
		(property "Reference" "Q89"
			(at 0 0 90)
			(layer "F.SilkS")
			(hide yes)
			(effects
				(font
					(size 1.27 1.27)
				)
			)
		)
		(property "Value" "2N7002A-7-GP"
			(at 0.127 -8.9662 90)
			(unlocked yes)
			(layer "F.Fab")
			(hide yes)
			(effects
				(font
					(size 1.016 1.016)
					(thickness 0.1524)
				)
			)
		)
		(property "Device Type" "SOT23DGS2D4H48"
			(at 0.127 -10.4902 90)
			(unlocked yes)
			(layer "F.Fab")
			(hide yes)
			(effects
				(font
					(size 1.016 1.016)
					(thickness 0.1524)
				)
			)
		)
		(duplicate_pad_numbers_are_jumpers no)
		(fp_line
			(start 1.651 -1.778)
			(end -1.651 -1.778)
			(stroke
				(width 0.1524)
				(type default)
			)
			(layer "F.SilkS")
		)
		(fp_line
			(start -1.651 -1.778)
			(end -1.651 1.778)
			(stroke
				(width 0.1524)
				(type default)
			)
			(layer "F.SilkS")
		)
		(fp_line
			(start 1.651 1.778)
			(end 1.651 -1.778)
			(stroke
				(width 0.1524)
				(type default)
			)
			(layer "F.SilkS")
		)
		(fp_line
			(start -1.651 1.778)
			(end 1.651 1.778)
			(stroke
				(width 0.1524)
				(type default)
			)
			(layer "F.SilkS")
		)
		(fp_poly
			(pts
				(xy -1.778 1.8796) (xy -1.778 -1.8796) (xy 1.778 -1.8796) (xy 1.778 1.8796)
			)
			(stroke
				(width 0)
				(type default)
			)
			(fill no)
			(layer "F.CrtYd")
		)
		(fp_poly
			(pts
				(xy -1.778 1.8796) (xy -1.778 -1.8796) (xy 1.778 -1.8796) (xy 1.778 1.8796)
			)
			(stroke
				(width 0)
				(type default)
			)
			(fill no)
			(layer "F.Fab")
		)
		(pad "D" smd custom
			(at 0 -0.9525 90)
			(size 0.1905 0.1905)
			(layers "F.Cu" "F.Mask" "F.Paste")
			(net "SSD12_CLK0_OE_MOS_N")
			(options
				(clearance outline)
				(anchor circle)
			)
			(primitives
				(gr_poly
					(pts
						(arc
							(start -0.1778 0.5715)
							(mid -0.321484 0.511984)
							(end -0.381 0.3683)
						)
						(arc
							(start -0.381 -0.3683)
							(mid -0.321484 -0.511984)
							(end -0.1778 -0.5715)
						)
						(arc
							(start 0.1778 -0.5715)
							(mid 0.321484 -0.511984)
							(end 0.381 -0.3683)
						)
						(arc
							(start 0.381 0.3683)
							(mid 0.321484 0.511984)
							(end 0.1778 0.5715)
						)
					)
					(width 0)
					(fill yes)
				)
			)
		)
		(pad "G" smd custom
			(at -0.98425 0.9525 90)
			(size 0.1905 0.1905)
			(layers "F.Cu" "F.Mask" "F.Paste")
			(net "SSD12_CLK0_OE_R_N")
			(options
				(clearance outline)
				(anchor circle)
			)
			(primitives
				(gr_poly
					(pts
						(arc
							(start -0.1778 0.5715)
							(mid -0.321484 0.511984)
							(end -0.381 0.3683)
						)
						(arc
							(start -0.381 -0.3683)
							(mid -0.321484 -0.511984)
							(end -0.1778 -0.5715)
						)
						(arc
							(start 0.1778 -0.5715)
							(mid 0.321484 -0.511984)
							(end 0.381 -0.3683)
						)
						(arc
							(start 0.381 0.3683)
							(mid 0.321484 0.511984)
							(end 0.1778 0.5715)
						)
					)
					(width 0)
					(fill yes)
				)
			)
		)
		(pad "S" smd custom
			(at 0.98425 0.9525 90)
			(size 0.1905 0.1905)
			(layers "F.Cu" "F.Mask" "F.Paste")
			(net "GND")
			(options
				(clearance outline)
				(anchor circle)
			)
			(primitives
				(gr_poly
					(pts
						(arc
							(start -0.1778 0.5715)
							(mid -0.321484 0.511984)
							(end -0.381 0.3683)
						)
						(arc
							(start -0.381 -0.3683)
							(mid -0.321484 -0.511984)
							(end -0.1778 -0.5715)
						)
						(arc
							(start 0.1778 -0.5715)
							(mid 0.321484 -0.511984)
							(end 0.381 -0.3683)
						)
						(arc
							(start 0.381 0.3683)
							(mid 0.321484 0.511984)
							(end 0.1778 0.5715)
						)
					)
					(width 0)
					(fill yes)
				)
			)
		)
	)
	(footprint ""
		(layer "F.Cu")
		(at 49.022 -454.787 -90)
		(property "Reference" "R9414"
			(at 0 0 270)
			(layer "F.SilkS")
			(hide yes)
			(effects
				(font
					(size 1.27 1.27)
				)
			)
		)
		(property "Value" "330R2F-GP"
			(at 0.064008 -3.993896 270)
			(unlocked yes)
			(layer "F.Fab")
			(hide yes)
			(effects
				(font
					(size 1.016 1.016)
					(thickness 0.1524)
				)
			)
		)
		(property "Device Type" "R402H16"
			(at 0.064008 -5.517896 270)
			(unlocked yes)
			(layer "F.Fab")
			(hide yes)
			(effects
				(font
					(size 1.016 1.016)
					(thickness 0.1524)
				)
			)
		)
		(duplicate_pad_numbers_are_jumpers no)
		(fp_line
			(start -0.508 -0.9398)
			(end -0.508 0.9398)
			(stroke
				(width 0.1524)
				(type default)
			)
			(layer "F.SilkS")
		)
		(fp_line
			(start 0.508 -0.9398)
			(end -0.508 -0.9398)
			(stroke
				(width 0.1524)
				(type default)
			)
			(layer "F.SilkS")
		)
		(fp_rect
			(start -0.508 0.9398)
			(end 0.508 -0.9398)
			(stroke
				(width 0)
				(type default)
			)
			(fill no)
			(layer "F.CrtYd")
		)
		(fp_rect
			(start -0.508 0.9398)
			(end 0.508 -0.9398)
			(stroke
				(width 0)
				(type default)
			)
			(fill no)
			(layer "F.Fab")
		)
		(pad "1" smd custom
			(at 0 -0.4445 270)
			(size 0.1397 0.1397)
			(layers "F.Cu" "F.Mask" "F.Paste")
			(net "P3V3")
			(options
				(clearance outline)
				(anchor circle)
			)
			(primitives
				(gr_poly
					(pts
						(arc
							(start -0.1778 -0.2794)
							(mid -0.249642 -0.249642)
							(end -0.2794 -0.1778)
						)
						(arc
							(start -0.2794 0.1778)
							(mid -0.249642 0.249642)
							(end -0.1778 0.2794)
						)
						(arc
							(start 0.1778 0.2794)
							(mid 0.249642 0.249642)
							(end 0.2794 0.1778)
						)
						(arc
							(start 0.2794 -0.1778)
							(mid 0.249642 -0.249642)
							(end 0.1778 -0.2794)
						)
					)
					(width 0)
					(fill yes)
				)
			)
		)
		(pad "2" smd custom
			(at 0 0.4445 270)
			(size 0.1397 0.1397)
			(layers "F.Cu" "F.Mask" "F.Paste")
			(net "DRV_ATTN_5")
			(options
				(clearance outline)
				(anchor circle)
			)
			(primitives
				(gr_poly
					(pts
						(arc
							(start -0.1778 -0.2794)
							(mid -0.249642 -0.249642)
							(end -0.2794 -0.1778)
						)
						(arc
							(start -0.2794 0.1778)
							(mid -0.249642 0.249642)
							(end -0.1778 0.2794)
						)
						(arc
							(start 0.1778 0.2794)
							(mid 0.249642 0.249642)
							(end 0.2794 0.1778)
						)
						(arc
							(start 0.2794 -0.1778)
							(mid 0.249642 -0.249642)
							(end 0.1778 -0.2794)
						)
					)
					(width 0)
					(fill yes)
				)
			)
		)
	)
	(footprint ""
		(layer "F.Cu")
		(at 206.67345 -95.95485 90)
		(property "Reference" "R9805"
			(at 0 0 90)
			(layer "F.SilkS")
			(hide yes)
			(effects
				(font
					(size 1.27 1.27)
				)
			)
		)
		(property "Value" "1KR2J-1-GP"
			(at 0.064008 -3.993896 90)
			(unlocked yes)
			(layer "F.Fab")
			(hide yes)
			(effects
				(font
					(size 1.016 1.016)
					(thickness 0.1524)
				)
			)
		)
		(property "Device Type" "R402H16"
			(at 0.064008 -5.517896 90)
			(unlocked yes)
			(layer "F.Fab")
			(hide yes)
			(effects
				(font
					(size 1.016 1.016)
					(thickness 0.1524)
				)
			)
		)
		(duplicate_pad_numbers_are_jumpers no)
		(fp_line
			(start 0.508 -0.9398)
			(end -0.508 -0.9398)
			(stroke
				(width 0.1524)
				(type default)
			)
			(layer "F.SilkS")
		)
		(fp_line
			(start -0.508 -0.9398)
			(end -0.508 0.9398)
			(stroke
				(width 0.1524)
				(type default)
			)
			(layer "F.SilkS")
		)
		(fp_rect
			(start -0.508 0.9398)
			(end 0.508 -0.9398)
			(stroke
				(width 0)
				(type default)
			)
			(fill no)
			(layer "F.CrtYd")
		)
		(fp_rect
			(start -0.508 0.9398)
			(end 0.508 -0.9398)
			(stroke
				(width 0)
				(type default)
			)
			(fill no)
			(layer "F.Fab")
		)
		(pad "1" smd custom
			(at 0 -0.4445 90)
			(size 0.1397 0.1397)
			(layers "F.Cu" "F.Mask" "F.Paste")
			(net "SSD4_PWREN")
			(options
				(clearance outline)
				(anchor circle)
			)
			(primitives
				(gr_poly
					(pts
						(arc
							(start -0.1778 -0.2794)
							(mid -0.249642 -0.249642)
							(end -0.2794 -0.1778)
						)
						(arc
							(start -0.2794 0.1778)
							(mid -0.249642 0.249642)
							(end -0.1778 0.2794)
						)
						(arc
							(start 0.1778 0.2794)
							(mid 0.249642 0.249642)
							(end 0.2794 0.1778)
						)
						(arc
							(start 0.2794 -0.1778)
							(mid 0.249642 -0.249642)
							(end 0.1778 -0.2794)
						)
					)
					(width 0)
					(fill yes)
				)
			)
		)
		(pad "2" smd custom
			(at 0 0.4445 90)
			(size 0.1397 0.1397)
			(layers "F.Cu" "F.Mask" "F.Paste")
			(net "SSD4_PWREN_R")
			(options
				(clearance outline)
				(anchor circle)
			)
			(primitives
				(gr_poly
					(pts
						(arc
							(start -0.1778 -0.2794)
							(mid -0.249642 -0.249642)
							(end -0.2794 -0.1778)
						)
						(arc
							(start -0.2794 0.1778)
							(mid -0.249642 0.249642)
							(end -0.1778 0.2794)
						)
						(arc
							(start 0.1778 0.2794)
							(mid 0.249642 0.249642)
							(end 0.2794 0.1778)
						)
						(arc
							(start 0.2794 -0.1778)
							(mid 0.249642 -0.249642)
							(end 0.1778 -0.2794)
						)
					)
					(width 0)
					(fill yes)
				)
			)
		)
	)
)
